(kicad_pcb
	(version 20221018)
	(generator pcbnew)
	(general
    (thickness 1.562)
  )
	(paper "A4")
	(title_block
    (title "Thunderbolt PCIe Adaper")
    (date "2024-07-09")
    (rev "1.0.3")
    (comment 1 "www.antmicro.com")
    (comment 2 "Antmicro Ltd.")
		(comment 9 "footprint 58 of 271 (U3), pads 1-93 of 96")
	)
	(layers
    (0 "F.Cu" signal)
    (1 "In1.Cu" signal)
    (2 "In2.Cu" signal)
    (3 "In3.Cu" signal)
    (4 "In4.Cu" signal)
    (31 "B.Cu" signal)
    (32 "B.Adhes" user "B.Adhesive")
    (33 "F.Adhes" user "F.Adhesive")
    (34 "B.Paste" user)
    (35 "F.Paste" user)
    (36 "B.SilkS" user "B.Silkscreen")
    (37 "F.SilkS" user "F.Silkscreen")
    (38 "B.Mask" user)
    (39 "F.Mask" user)
    (40 "Dwgs.User" user "User.Drawings")
    (41 "Cmts.User" user "User.Comments")
    (42 "Eco1.User" user "User.Eco1")
    (43 "Eco2.User" user "User.Eco2")
    (44 "Edge.Cuts" user)
    (45 "Margin" user)
    (46 "B.CrtYd" user "B.Courtyard")
    (47 "F.CrtYd" user "F.Courtyard")
    (48 "B.Fab" user)
    (49 "F.Fab" user)
  )
	(footprint "antmicro-footprints:IC_TPS65983BAZBHR"
    (layer "F.Cu")
    (at 156.89 62.85)
    (property "Author" "Antmicro")
    (property "License" "Apache-2.0")
    (property "MPN" "TPS65983BAZBHR")
    (property "Manufacturer" "Texas Instruments")
    (property "Sheetfile" "power.kicad_sch")
    (property "Sheetname" "Power")
    (property "ki_description" "USB Interface IC Universal USB Type-C and Power Delivery (PD) 3.0 controller 96-NFBGA -10°C to 85")
    (property "ki_keywords" "IC")
    (attr smd)
    (fp_text reference "U3" (at 0 -3.8 unlocked) (layer "F.SilkS")
        (effects (font (size 0.7 0.7) (thickness 0.15)))
    )
    (fp_text value "TPS65983BAZBHR" (at 0 4.1 unlocked) (layer "F.Fab")
        (effects (font (size 0.7 0.7) (thickness 0.15)))
    )
    (pad "A1" smd circle (at -2.5 -2.5) (size 0.25 0.25) (layers "F.Cu" "F.Paste" "F.Mask")
      (net 1 "GND") (pinfunction "GND") (pintype "power_in") (solder_paste_margin_ratio -1))
    (pad "A2" smd oval (at -2 -2.5) (size 0.17 0.25) (layers "F.Cu" "F.Paste" "F.Mask")
      (net 103 "Net-(U3-LDO_1V8D)") (pinfunction "LDO_1V8D") (pintype "power_out"))
    (pad "A3" smd oval (at -1.5 -2.5) (size 0.17 0.25) (layers "F.Cu" "F.Paste" "F.Mask")
      (net 68 "SPI_SCLK") (pinfunction "SPI_CLK") (pintype "output"))
    (pad "A4" smd oval (at -1 -2.5) (size 0.17 0.25) (layers "F.Cu" "F.Paste" "F.Mask")
      (net 63 "SPI_MISO") (pinfunction "SPI_POCI") (pintype "input"))
    (pad "A5" smd oval (at -0.5 -2.5) (size 0.17 0.25) (layers "F.Cu" "F.Paste" "F.Mask")
      (net 149 "Net-(U3-I2C_SDA2)") (pinfunction "I2C_SDA2") (pintype "bidirectional"))
    (pad "A6" smd oval (at 0 -2.5) (size 0.17 0.25) (layers "F.Cu" "F.Paste" "F.Mask")
      (net 19 "PP_HV") (pinfunction "PP_HV") (pintype "power_in"))
    (pad "A7" smd oval (at 0.5 -2.5) (size 0.17 0.25) (layers "F.Cu" "F.Paste" "F.Mask")
      (net 19 "PP_HV") (pinfunction "PP_HV") (pintype "power_in"))
    (pad "A8" smd oval (at 1 -2.5) (size 0.17 0.25) (layers "F.Cu" "F.Paste" "F.Mask")
      (net 19 "PP_HV") (pinfunction "PP_HV") (pintype "power_in"))
    (pad "A9" smd oval (at 1.5 -2.5) (size 0.17 0.25) (layers "F.Cu" "F.Paste" "F.Mask")
      (net 208 "unconnected-(U3-HV_GATE2-PadA9)") (pinfunction "HV_GATE2") (pintype "output+no_connect"))
    (pad "A10" smd oval (at 2 -2.5) (size 0.17 0.25) (layers "F.Cu" "F.Paste" "F.Mask")
      (net 209 "unconnected-(U3-SENSEN-PadA10)") (pinfunction "SENSEN") (pintype "input+no_connect"))
    (pad "A11" smd circle (at 2.5 -2.5) (size 0.25 0.25) (layers "F.Cu" "F.Paste" "F.Mask")
      (net 20 "PP_5V0") (pinfunction "PP_5V0") (pintype "power_in") (solder_paste_margin_ratio -1))
    (pad "B1" smd oval (at -2.5 -2) (size 0.25 0.17) (layers "F.Cu" "F.Paste" "F.Mask")
      (net 2 "3V3_SYS") (pinfunction "VDDIO") (pintype "power_in"))
    (pad "B2" smd circle (at -2 -2 270) (size 0.25 0.25) (layers "F.Cu" "F.Paste" "F.Mask")
      (net 152 "Net-(U3-GPIO0(HD3_AMSEL))") (pinfunction "GPIO0(HD3_AMSEL)") (pintype "bidirectional") (solder_paste_margin_ratio -1))
    (pad "B3" smd circle (at -1.5 -2) (size 0.25 0.25) (layers "F.Cu" "F.Paste" "F.Mask")
      (net 65 "SPI_CS") (pinfunction "SPI_CSZ") (pintype "output") (solder_paste_margin_ratio -1))
    (pad "B4" smd circle (at -1 -2) (size 0.25 0.25) (layers "F.Cu" "F.Paste" "F.Mask")
      (net 69 "SPI_MOSI") (pinfunction "SPI_PICO") (pintype "output") (solder_paste_margin_ratio -1))
    (pad "B5" smd circle (at -0.5 -2 90) (size 0.25 0.25) (layers "F.Cu" "F.Paste" "F.Mask")
      (net 150 "Net-(U3-I2C_SCL2)") (pinfunction "I2C_SCL2") (pintype "bidirectional") (solder_paste_margin_ratio -1))
    (pad "B6" smd circle (at 0 -2 90) (size 0.25 0.25) (layers "F.Cu" "F.Paste" "F.Mask")
      (net 151 "Net-(U3-I2C_IRQ2Z)") (pinfunction "I2C_IRQ2Z") (pintype "output") (solder_paste_margin_ratio -1))
    (pad "B7" smd circle (at 0.5 -2) (size 0.25 0.25) (layers "F.Cu" "F.Paste" "F.Mask")
      (net 19 "PP_HV") (pinfunction "PP_HV") (pintype "power_in") (solder_paste_margin_ratio -1))
    (pad "B8" smd circle (at 1 -2) (size 0.25 0.25) (layers "F.Cu" "F.Paste" "F.Mask")
      (net 1 "GND") (pinfunction "GND") (pintype "power_in") (solder_paste_margin_ratio -1))
    (pad "B9" smd circle (at 1.5 -2) (size 0.25 0.25) (layers "F.Cu" "F.Paste" "F.Mask")
      (net 210 "unconnected-(U3-HV_GATE1-PadB9)") (pinfunction "HV_GATE1") (pintype "output+no_connect") (solder_paste_margin_ratio -1))
    (pad "B10" smd circle (at 2 -2) (size 0.25 0.25) (layers "F.Cu" "F.Paste" "F.Mask")
      (net 211 "unconnected-(U3-SENSEP-PadB10)") (pinfunction "SENSEP") (pintype "input+no_connect") (solder_paste_margin_ratio -1))
    (pad "B11" smd oval (at 2.5 -2) (size 0.25 0.17) (layers "F.Cu" "F.Paste" "F.Mask")
      (net 20 "PP_5V0") (pinfunction "PP_5V0") (pintype "power_in"))
    (pad "C1" smd oval (at -2.5 -1.5) (size 0.25 0.17) (layers "F.Cu" "F.Paste" "F.Mask")
      (net 56 "I2C1_IRQ") (pinfunction "I2C_IRQ1Z") (pintype "output"))
    (pad "C2" smd circle (at -2 -1.5 270) (size 0.25 0.25) (layers "F.Cu" "F.Paste" "F.Mask")
      (net 212 "unconnected-(U3-GPIO1(CONFIG0)-PadC2)") (pinfunction "GPIO1(CONFIG0)") (pintype "bidirectional+no_connect") (solder_paste_margin_ratio -1))
    (pad "C10" smd circle (at 2 -1.5 90) (size 0.25 0.25) (layers "F.Cu" "F.Paste" "F.Mask")
      (net 153 "Net-(U3-GPIO4(HPD_TXRX))") (pinfunction "GPIO4(HPD_TXRX)") (pintype "bidirectional") (solder_paste_margin_ratio -1))
    (pad "C11" smd oval (at 2.5 -1.5) (size 0.25 0.17) (layers "F.Cu" "F.Paste" "F.Mask")
      (net 20 "PP_5V0") (pinfunction "PP_5V0") (pintype "power_in"))
    (pad "D1" smd oval (at -2.5 -1) (size 0.25 0.17) (layers "F.Cu" "F.Paste" "F.Mask")
      (net 59 "I2C1_SDA") (pinfunction "I2C_SDA1") (pintype "bidirectional"))
    (pad "D2" smd circle (at -2 -1 270) (size 0.25 0.25) (layers "F.Cu" "F.Paste" "F.Mask")
      (net 57 "I2C1_SCL") (pinfunction "I2C_SCL1") (pintype "bidirectional") (solder_paste_margin_ratio -1))
    (pad "D5" smd circle (at -0.5 -1 180) (size 0.25 0.25) (layers "F.Cu" "F.Paste" "F.Mask")
      (net 162 "Net-(U3-DEBUG_CTL2(GPIO17,_I2CADDR_B5))") (pinfunction "DEBUG_CTL2(GPIO17,_I2CADDR_B5)") (pintype "bidirectional") (solder_paste_margin_ratio -1))
    (pad "D6" smd circle (at 0 -1 180) (size 0.25 0.25) (layers "F.Cu" "F.Paste" "F.Mask")
      (net 166 "Net-(U3-HRESET)") (pinfunction "HRESET") (pintype "input") (solder_paste_margin_ratio -1))
    (pad "D7" smd circle (at 0.5 -1 180) (size 0.25 0.25) (layers "F.Cu" "F.Paste" "F.Mask")
      (net 155 "Net-(U3-GPIO7)") (pinfunction "GPIO7") (pintype "bidirectional") (solder_paste_margin_ratio -1))
    (pad "D8" smd circle (at 1 -1 180) (size 0.25 0.25) (layers "F.Cu" "F.Paste" "F.Mask")
      (net 1 "GND") (pinfunction "GND") (pintype "power_in") (solder_paste_margin_ratio -1))
    (pad "D10" smd circle (at 2 -1 90) (size 0.25 0.25) (layers "F.Cu" "F.Paste" "F.Mask")
      (net 213 "unconnected-(U3-GPIO2-PadD10)") (pinfunction "GPIO2") (pintype "bidirectional+no_connect") (solder_paste_margin_ratio -1))
    (pad "D11" smd oval (at 2.5 -1) (size 0.25 0.17) (layers "F.Cu" "F.Paste" "F.Mask")
      (net 20 "PP_5V0") (pinfunction "PP_5V0") (pintype "power_in"))
    (pad "E1" smd oval (at -2.5 -0.5) (size 0.25 0.17) (layers "F.Cu" "F.Paste" "F.Mask")
      (net 104 "Net-(U3-LDO_BMC)") (pinfunction "LDO_BMC") (pintype "power_out"))
    (pad "E2" smd circle (at -2 -0.5) (size 0.25 0.25) (layers "F.Cu" "F.Paste" "F.Mask")
      (net 156 "Net-(U3-UART_RX)") (pinfunction "UART_TX") (pintype "output") (solder_paste_margin_ratio -1))
    (pad "E4" smd circle (at -1 -0.5) (size 0.25 0.25) (layers "F.Cu" "F.Paste" "F.Mask")
      (net 163 "Net-(U3-DEBUG_CTL1(GPIO16,_I2CADDR_B4))") (pinfunction "DEBUG_CTL1(GPIO16,_I2CADDR_B4)") (pintype "bidirectional") (solder_paste_margin_ratio -1))
    (pad "E5" smd circle (at -0.5 -0.5) (size 0.25 0.25) (layers "F.Cu" "F.Paste" "F.Mask")
      (net 1 "GND") (pinfunction "GND") (pintype "power_in") (solder_paste_margin_ratio -1))
    (pad "E6" smd circle (at 0 -0.5 180) (size 0.25 0.25) (layers "F.Cu" "F.Paste" "F.Mask")
      (net 1 "GND") (pinfunction "GND") (pintype "power_in") (solder_paste_margin_ratio -1))
    (pad "E7" smd circle (at 0.5 -0.5 180) (size 0.25 0.25) (layers "F.Cu" "F.Paste" "F.Mask")
      (net 1 "GND") (pinfunction "GND") (pintype "power_in") (solder_paste_margin_ratio -1))
    (pad "E8" smd circle (at 1 -0.5 180) (size 0.25 0.25) (layers "F.Cu" "F.Paste" "F.Mask")
      (net 1 "GND") (pinfunction "GND") (pintype "power_in") (solder_paste_margin_ratio -1))
    (pad "E10" smd circle (at 2 -0.5 90) (size 0.25 0.25) (layers "F.Cu" "F.Paste" "F.Mask")
      (net 214 "unconnected-(U3-GPIO5(HPD_RX)-PadE10)") (pinfunction "GPIO5(HPD_RX)") (pintype "bidirectional+no_connect") (solder_paste_margin_ratio -1))
    (pad "E11" smd oval (at 2.5 -0.5) (size 0.25 0.17) (layers "F.Cu" "F.Paste" "F.Mask")
      (net 165 "Net-(U3-MRESET(GPIO11))") (pinfunction "MRESET(GPIO11)") (pintype "bidirectional"))
    (pad "F1" smd oval (at -2.5 0) (size 0.25 0.17) (layers "F.Cu" "F.Paste" "F.Mask")
      (net 164 "Net-(U3-I2C_ADDR)") (pinfunction "I2C_ADDR") (pintype "bidirectional"))
    (pad "F2" smd circle (at -2 0) (size 0.25 0.25) (layers "F.Cu" "F.Paste" "F.Mask")
      (net 156 "Net-(U3-UART_RX)") (pinfunction "UART_RX") (pintype "input") (solder_paste_margin_ratio -1))
    (pad "F4" smd circle (at -1 0 270) (size 0.25 0.25) (layers "F.Cu" "F.Paste" "F.Mask")
      (net 215 "unconnected-(U3-SWD_DATA-PadF4)") (pinfunction "SWD_DATA") (pintype "bidirectional+no_connect") (solder_paste_margin_ratio -1))
    (pad "F5" smd circle (at -0.5 0 270) (size 0.25 0.25) (layers "F.Cu" "F.Paste" "F.Mask")
      (net 1 "GND") (pinfunction "GND") (pintype "power_in") (solder_paste_margin_ratio -1))
    (pad "F6" smd circle (at 0 0 180) (size 0.25 0.25) (layers "F.Cu" "F.Paste" "F.Mask")
      (net 1 "GND") (pinfunction "GND") (pintype "power_in") (solder_paste_margin_ratio -1))
    (pad "F7" smd circle (at 0.5 0) (size 0.25 0.25) (layers "F.Cu" "F.Paste" "F.Mask")
      (net 1 "GND") (pinfunction "GND") (pintype "power_in") (solder_paste_margin_ratio -1))
    (pad "F8" smd circle (at 1 0) (size 0.25 0.25) (layers "F.Cu" "F.Paste" "F.Mask")
      (net 1 "GND") (pinfunction "GND") (pintype "power_in") (solder_paste_margin_ratio -1))
    (pad "F10" smd circle (at 2 0 180) (size 0.25 0.25) (layers "F.Cu" "F.Paste" "F.Mask")
      (net 167 "Net-(U3-BUSPOWERZ(GPIO10))") (pinfunction "BUSPOWERZ(GPIO10)") (pintype "bidirectional") (solder_paste_margin_ratio -1))
    (pad "F11" smd oval (at 2.5 0) (size 0.25 0.17) (layers "F.Cu" "F.Paste" "F.Mask")
      (net 62 "RESET_N") (pinfunction "RESETZ(GPIO9)") (pintype "bidirectional"))
    (pad "G1" smd oval (at -2.5 0.5) (size 0.25 0.17) (layers "F.Cu" "F.Paste" "F.Mask")
      (net 9 "/Power/TPS_3V3") (pinfunction "LDO_3V3") (pintype "power_out"))
    (pad "G2" smd circle (at -2 0.5 270) (size 0.25 0.25) (layers "F.Cu" "F.Paste" "F.Mask")
      (net 168 "Net-(U3-R_OSC)") (pinfunction "R_OSC") (pintype "bidirectional") (solder_paste_margin_ratio -1))
    (pad "G4" smd circle (at -1 0.5 270) (size 0.25 0.25) (layers "F.Cu" "F.Paste" "F.Mask")
      (net 216 "unconnected-(U3-SWD_CLK-PadG4)") (pinfunction "SWD_CLK") (pintype "input+no_connect") (solder_paste_margin_ratio -1))
    (pad "G5" smd circle (at -0.5 0.5 270) (size 0.25 0.25) (layers "F.Cu" "F.Paste" "F.Mask")
      (net 1 "GND") (pinfunction "GND") (pintype "power_in") (solder_paste_margin_ratio -1))
    (pad "G6" smd circle (at 0 0.5 180) (size 0.25 0.25) (layers "F.Cu" "F.Paste" "F.Mask")
      (net 1 "GND") (pinfunction "GND") (pintype "power_in") (solder_paste_margin_ratio -1))
    (pad "G7" smd circle (at 0.5 0.5 270) (size 0.25 0.25) (layers "F.Cu" "F.Paste" "F.Mask")
      (net 1 "GND") (pinfunction "GND") (pintype "power_in") (solder_paste_margin_ratio -1))
    (pad "G8" smd circle (at 1 0.5) (size 0.25 0.25) (layers "F.Cu" "F.Paste" "F.Mask")
      (net 1 "GND") (pinfunction "GND") (pintype "power_in") (solder_paste_margin_ratio -1))
    (pad "G10" smd circle (at 2 0.5 90) (size 0.25 0.25) (layers "F.Cu" "F.Paste" "F.Mask")
      (net 154 "Net-(U3-GPIO6)") (pinfunction "GPIO6") (pintype "bidirectional") (solder_paste_margin_ratio -1))
    (pad "G11" smd oval (at 2.5 0.5) (size 0.25 0.17) (layers "F.Cu" "F.Paste" "F.Mask")
      (net 217 "unconnected-(U3-GPIO3(HD3_EN)-PadG11)") (pinfunction "GPIO3(HD3_EN)") (pintype "bidirectional+no_connect"))
    (pad "H1" smd oval (at -2.5 1) (size 0.25 0.17) (layers "F.Cu" "F.Paste" "F.Mask")
      (net 2 "3V3_SYS") (pinfunction "VIN_3V3") (pintype "power_in"))
    (pad "H2" smd circle (at -2 1 270) (size 0.25 0.25) (layers "F.Cu" "F.Paste" "F.Mask")
      (net 101 "Net-(U3-VOUT_3V3)") (pinfunction "VOUT_3V3") (pintype "power_out") (solder_paste_margin_ratio -1))
    (pad "H4" smd circle (at -1 1 270) (size 0.25 0.25) (layers "F.Cu" "F.Paste" "F.Mask")
      (net 1 "GND") (pinfunction "GND") (pintype "power_in") (solder_paste_margin_ratio -1))
    (pad "H5" smd circle (at -0.5 1 270) (size 0.25 0.25) (layers "F.Cu" "F.Paste" "F.Mask")
      (net 1 "GND") (pinfunction "GND") (pintype "power_in") (solder_paste_margin_ratio -1))
    (pad "H6" smd circle (at 0 1 180) (size 0.25 0.25) (layers "F.Cu" "F.Paste" "F.Mask")
      (net 218 "unconnected-(U3-GPIO8-PadH6)") (pinfunction "GPIO8") (pintype "bidirectional+no_connect") (solder_paste_margin_ratio -1))
    (pad "H7" smd circle (at 0.5 1 180) (size 0.25 0.25) (layers "F.Cu" "F.Paste" "F.Mask")
      (net 98 "Net-(U3-SS)") (pinfunction "SS") (pintype "output") (solder_paste_margin_ratio -1))
    (pad "H8" smd circle (at 1 1 270) (size 0.25 0.25) (layers "F.Cu" "F.Paste" "F.Mask")
      (net 1 "GND") (pinfunction "GND") (pintype "power_in") (solder_paste_margin_ratio -1))
    (pad "H10" smd circle (at 2 1 90) (size 0.25 0.25) (layers "F.Cu" "F.Paste" "F.Mask")
      (net 20 "PP_5V0") (pinfunction "PP_CABLE") (pintype "power_in") (solder_paste_margin_ratio -1))
    (pad "H11" smd oval (at 2.5 1) (size 0.25 0.17) (layers "F.Cu" "F.Paste" "F.Mask")
      (net 32 "VBUS") (pinfunction "VBUS") (pintype "power_in"))
    (pad "J1" smd oval (at -2.5 1.5) (size 0.25 0.17) (layers "F.Cu" "F.Paste" "F.Mask")
      (net 16 "AUX_P") (pinfunction "AUX_P") (pintype "bidirectional"))
    (pad "J2" smd circle (at -2 1.5 270) (size 0.25 0.25) (layers "F.Cu" "F.Paste" "F.Mask")
      (net 23 "AUX_N") (pinfunction "AUX_N") (pintype "bidirectional") (solder_paste_margin_ratio -1))
    (pad "J10" smd circle (at 2 1.5 90) (size 0.25 0.25) (layers "F.Cu" "F.Paste" "F.Mask")
      (net 32 "VBUS") (pinfunction "VBUS") (pintype "power_in") (solder_paste_margin_ratio -1))
    (pad "J11" smd oval (at 2.5 1.5) (size 0.25 0.17) (layers "F.Cu" "F.Paste" "F.Mask")
      (net 32 "VBUS") (pinfunction "VBUS") (pintype "power_in"))
    (pad "K1" smd oval (at -2.5 2) (size 0.25 0.17) (layers "F.Cu" "F.Paste" "F.Mask")
      (net 102 "Net-(U3-LDO_1V8A)") (pinfunction "LDO_1V8A") (pintype "power_out"))
    (pad "K2" smd circle (at -2 2 180) (size 0.25 0.25) (layers "F.Cu" "F.Paste" "F.Mask")
      (net 1 "GND") (pinfunction "DEBUG2(GPIO14,HD3POL)") (pintype "bidirectional") (solder_paste_margin_ratio -1))
    (pad "K3" smd circle (at -1.5 2 180) (size 0.25 0.25) (layers "F.Cu" "F.Paste" "F.Mask")
      (net 1 "GND") (pinfunction "DEBUG4(GPIO12,CONFIG2)") (pintype "bidirectional") (solder_paste_margin_ratio -1))
    (pad "K4" smd circle (at -1 2 270) (size 0.25 0.25) (layers "F.Cu" "F.Paste" "F.Mask")
      (net 66 "LSX_P2R") (pinfunction "LSX_P2R") (pintype "output") (solder_paste_margin_ratio -1))
    (pad "K5" smd circle (at -0.5 2 270) (size 0.25 0.25) (layers "F.Cu" "F.Paste" "F.Mask")
      (net 70 "USB_RP_N") (pinfunction "USB_RP_N") (pintype "bidirectional") (solder_paste_margin_ratio -1))
    (pad "K6" smd circle (at 0 2 180) (size 0.25 0.25) (layers "F.Cu" "F.Paste" "F.Mask")
      (net 33 "USB_T_P") (pinfunction "C_USB_TP") (pintype "bidirectional") (solder_paste_margin_ratio -1))
    (pad "K7" smd circle (at 0.5 2 180) (size 0.25 0.25) (layers "F.Cu" "F.Paste" "F.Mask")
      (net 38 "USB_B_P") (pinfunction "C_USB_BP") (pintype "bidirectional") (solder_paste_margin_ratio -1))
    (pad "K8" smd circle (at 1 2 180) (size 0.25 0.25) (layers "F.Cu" "F.Paste" "F.Mask")
      (net 35 "SBU1") (pinfunction "C_SBU1") (pintype "bidirectional") (solder_paste_margin_ratio -1))
    (pad "K9" smd circle (at 1.5 2 180) (size 0.25 0.25) (layers "F.Cu" "F.Paste" "F.Mask")
      (net 1 "GND") (pinfunction "RPD_G1") (pintype "bidirectional") (solder_paste_margin_ratio -1))
    (pad "K10" smd circle (at 2 2 270) (size 0.25 0.25) (layers "F.Cu" "F.Paste" "F.Mask")
      (net 1 "GND") (pinfunction "RPD_G2") (pintype "bidirectional") (solder_paste_margin_ratio -1))
    (pad "K11" smd oval (at 2.5 2) (size 0.25 0.17) (layers "F.Cu" "F.Paste" "F.Mask")
      (net 32 "VBUS") (pinfunction "VBUS") (pintype "power_in"))
    (pad "L1" smd circle (at -2.5 2.5 270) (size 0.25 0.25) (layers "F.Cu" "F.Paste" "F.Mask")
      (net 1 "GND") (pinfunction "GND") (pintype "power_in") (solder_paste_margin_ratio -1))
    (pad "L2" smd oval (at -2 2.5) (size 0.17 0.25) (layers "F.Cu" "F.Paste" "F.Mask")
      (net 1 "GND") (pinfunction "DEBUG1(GPIO15)") (pintype "bidirectional"))
    (pad "L3" smd oval (at -1.5 2.5) (size 0.17 0.25) (layers "F.Cu" "F.Paste" "F.Mask")
      (net 1 "GND") (pinfunction "DEBUG3(GPIO13,CONFIG1)") (pintype "bidirectional"))
    (pad "L4" smd oval (at -1 2.5) (size 0.17 0.25) (layers "F.Cu" "F.Paste" "F.Mask")
      (net 67 "LSX_R2P") (pinfunction "LSX_R2P") (pintype "input"))
    (pad "L5" smd oval (at -0.5 2.5) (size 0.17 0.25) (layers "F.Cu" "F.Paste" "F.Mask")
      (net 71 "USB_RP_P") (pinfunction "USB_RP_P") (pintype "bidirectional"))
    (pad "L6" smd oval (at 0 2.5) (size 0.17 0.25) (layers "F.Cu" "F.Paste" "F.Mask")
      (net 34 "USB_T_N") (pinfunction "C_USB_TN") (pintype "bidirectional"))
    (pad "L7" smd oval (at 0.5 2.5) (size 0.17 0.25) (layers "F.Cu" "F.Paste" "F.Mask")
      (net 39 "USB_B_N") (pinfunction "C_USB_BN") (pintype "bidirectional"))
    (pad "L8" smd oval (at 1 2.5) (size 0.17 0.25) (layers "F.Cu" "F.Paste" "F.Mask")
      (net 40 "SBU2") (pinfunction "C_SBU2") (pintype "bidirectional"))
  )
)
